(kicad_pcb
	(version 20260206)
	(generator "pcbnew")
	(generator_version "10.0")
	(general
		(thickness 1.21888)
		(legacy_teardrops no)
	)
	(paper "A4")
	(title_block
		(title "timecard-proto-v0 — Timingcard_PCB.PcbDoc")
		(comment 1 "Time Appliance Project (Time Card) / footprints 92-100 of 167")
	)
	(layers
		(0 "F.Cu" signal "TOP")
		(4 "In1.Cu" signal "SGND")
		(6 "In2.Cu" signal "IN1")
		(8 "In3.Cu" signal "IN2")
		(10 "In4.Cu" signal "SGND1")
		(2 "B.Cu" signal "BOTTOM")
		(9 "F.Adhes" user "F.Adhesive")
		(11 "B.Adhes" user "B.Adhesive")
		(13 "F.Paste" user "Top Paste")
		(15 "B.Paste" user "Bottom Paste")
		(5 "F.SilkS" user "Top Overlay")
		(7 "B.SilkS" user "Bottom Overlay")
		(1 "F.Mask" user "Top Solder")
		(3 "B.Mask" user "Bottom Solder")
		(17 "Dwgs.User" user "User.Drawings")
		(19 "Cmts.User" user "User.Comments")
		(21 "Eco1.User" user "User.Eco1")
		(23 "Eco2.User" user "User.Eco2")
		(25 "Edge.Cuts" user)
		(27 "Margin" user)
		(31 "F.CrtYd" user "Top Courtyard")
		(29 "B.CrtYd" user "Bottom Courtyard")
		(35 "F.Fab" user "Top Component Center")
		(33 "B.Fab" user "Bottom Component Center")
	)
	(footprint "Connectors:PCIE_4LANE_EDGE"
		(layer "F.Cu")
		(at 120.638465 154.3547)
		(property "Reference" "P2"
			(at -12.64987 -0.282755 0)
			(unlocked yes)
			(layer "F.SilkS")
			(hide yes)
			(effects
				(font
					(size 0.762 0.762)
					(thickness 0.2286)
				)
				(justify left bottom)
			)
		)
		(property "Value" "PCIex4"
			(at -5.44907 18.65122 0)
			(unlocked yes)
			(layer "F.SilkS")
			(hide yes)
			(effects
				(font
					(size 1.524 1.524)
					(thickness 0.254)
				)
				(justify left bottom)
			)
		)
		(sheetname "PCIe_JTAG")
		(sheetfile "PCIe_JTAG.kicad_sch")
		(duplicate_pad_numbers_are_jumpers no)
		(pad "A1" smd rect
			(at -16.49984 2.2286)
			(size 0.7112 3.2004)
			(layers "B.Cu" "B.Mask" "B.Paste")
			(net "PRSNT")
		)
		(pad "A2" smd rect
			(at -15.49985 2.7239)
			(size 0.7112 4.191)
			(layers "B.Cu" "B.Mask" "B.Paste")
			(net "+12V_PCIE")
		)
		(pad "A3" smd rect
			(at -14.49985 2.7239)
			(size 0.7112 4.191)
			(layers "B.Cu" "B.Mask" "B.Paste")
			(net "+12V_PCIE")
		)
		(pad "A4" smd rect
			(at -13.49985 2.7239)
			(size 0.7112 4.191)
			(layers "B.Cu" "B.Mask" "B.Paste")
			(net "GND")
		)
		(pad "A5" smd rect
			(at -12.49985 2.7239)
			(size 0.7112 4.191)
			(layers "B.Cu" "B.Mask" "B.Paste")
		)
		(pad "A6" smd rect
			(at -11.49985 2.7239)
			(size 0.7112 4.191)
			(layers "B.Cu" "B.Mask" "B.Paste")
		)
		(pad "A7" smd rect
			(at -10.49986 2.7239)
			(size 0.7112 4.191)
			(layers "B.Cu" "B.Mask" "B.Paste")
		)
		(pad "A8" smd rect
			(at -9.49986 2.7239)
			(size 0.7112 4.191)
			(layers "B.Cu" "B.Mask" "B.Paste")
		)
		(pad "A9" smd rect
			(at -8.49986 2.7239)
			(size 0.7112 4.191)
			(layers "B.Cu" "B.Mask" "B.Paste")
			(net "+3.3V_PCIE")
		)
		(pad "A10" smd rect
			(at -7.49986 2.7239)
			(size 0.7112 4.191)
			(layers "B.Cu" "B.Mask" "B.Paste")
			(net "+3.3V_PCIE")
		)
		(pad "A11" smd rect
			(at -6.49986 2.7239)
			(size 0.7112 4.191)
			(layers "B.Cu" "B.Mask" "B.Paste")
			(net "PCIE_PERST")
		)
		(pad "A12" smd rect
			(at -3.49987 2.7239)
			(size 0.7112 4.191)
			(layers "B.Cu" "B.Mask" "B.Paste")
			(net "GND")
		)
		(pad "A13" smd rect
			(at -2.49987 2.7239)
			(size 0.7112 4.191)
			(layers "B.Cu" "B.Mask" "B.Paste")
			(net "NetC44_1")
		)
		(pad "A14" smd rect
			(at -1.49987 2.7239)
			(size 0.7112 4.191)
			(layers "B.Cu" "B.Mask" "B.Paste")
			(net "NetC45_1")
		)
		(pad "A15" smd rect
			(at -0.49988 2.7239)
			(size 0.7112 4.191)
			(layers "B.Cu" "B.Mask" "B.Paste")
			(net "GND")
		)
		(pad "A16" smd rect
			(at 0.50012 2.7239)
			(size 0.7112 4.191)
			(layers "B.Cu" "B.Mask" "B.Paste")
			(net "NetC46_1")
		)
		(pad "A17" smd rect
			(at 1.50012 2.7239)
			(size 0.7112 4.191)
			(layers "B.Cu" "B.Mask" "B.Paste")
			(net "NetC47_1")
		)
		(pad "A18" smd rect
			(at 2.50012 2.7239)
			(size 0.7112 4.191)
			(layers "B.Cu" "B.Mask" "B.Paste")
			(net "GND")
		)
		(pad "A19" smd rect
			(at 3.50012 2.7239)
			(size 0.7112 4.191)
			(layers "B.Cu" "B.Mask" "B.Paste")
		)
		(pad "A20" smd rect
			(at 4.50011 2.7239)
			(size 0.7112 4.191)
			(layers "B.Cu" "B.Mask" "B.Paste")
			(net "GND")
		)
		(pad "A21" smd rect
			(at 5.50011 2.7239)
			(size 0.7112 4.191)
			(layers "B.Cu" "B.Mask" "B.Paste")
			(net "NetC48_1")
		)
		(pad "A22" smd rect
			(at 6.50011 2.7239)
			(size 0.7112 4.191)
			(layers "B.Cu" "B.Mask" "B.Paste")
			(net "NetC49_1")
		)
		(pad "A23" smd rect
			(at 7.50011 2.7239)
			(size 0.7112 4.191)
			(layers "B.Cu" "B.Mask" "B.Paste")
			(net "GND")
		)
		(pad "A24" smd rect
			(at 8.50011 2.7239)
			(size 0.7112 4.191)
			(layers "B.Cu" "B.Mask" "B.Paste")
			(net "GND")
		)
		(pad "A25" smd rect
			(at 9.5001 2.7239)
			(size 0.7112 4.191)
			(layers "B.Cu" "B.Mask" "B.Paste")
			(net "NetC50_1")
		)
		(pad "A26" smd rect
			(at 10.5001 2.7239)
			(size 0.7112 4.191)
			(layers "B.Cu" "B.Mask" "B.Paste")
			(net "NetC51_1")
		)
		(pad "A27" smd rect
			(at 11.5001 2.7239)
			(size 0.7112 4.191)
			(layers "B.Cu" "B.Mask" "B.Paste")
			(net "GND")
		)
		(pad "A28" smd rect
			(at 12.5001 2.7239)
			(size 0.7112 4.191)
			(layers "B.Cu" "B.Mask" "B.Paste")
			(net "GND")
		)
		(pad "A29" smd rect
			(at 13.5001 2.7239)
			(size 0.7112 4.191)
			(layers "B.Cu" "B.Mask" "B.Paste")
			(net "NetC52_1")
		)
		(pad "A30" smd rect
			(at 14.50009 2.7239)
			(size 0.7112 4.191)
			(layers "B.Cu" "B.Mask" "B.Paste")
			(net "NetC53_1")
		)
		(pad "A31" smd rect
			(at 15.50009 2.7239)
			(size 0.7112 4.191)
			(layers "B.Cu" "B.Mask" "B.Paste")
			(net "GND")
		)
		(pad "A32" smd rect
			(at 16.50009 2.7239)
			(size 0.7112 4.191)
			(layers "B.Cu" "B.Mask" "B.Paste")
		)
		(pad "B1" smd rect
			(at -16.49984 2.7239)
			(size 0.7112 4.191)
			(layers "F.Cu" "F.Mask" "F.Paste")
			(net "+12V_PCIE")
		)
		(pad "B2" smd rect
			(at -15.49985 2.7239)
			(size 0.7112 4.191)
			(layers "F.Cu" "F.Mask" "F.Paste")
			(net "+12V_PCIE")
		)
		(pad "B3" smd rect
			(at -14.49985 2.7239)
			(size 0.7112 4.191)
			(layers "F.Cu" "F.Mask" "F.Paste")
			(net "+12V_PCIE")
		)
		(pad "B4" smd rect
			(at -13.49985 2.7239)
			(size 0.7112 4.191)
			(layers "F.Cu" "F.Mask" "F.Paste")
			(net "GND")
		)
		(pad "B5" smd rect
			(at -12.49985 2.7239)
			(size 0.7112 4.191)
			(layers "F.Cu" "F.Mask" "F.Paste")
		)
		(pad "B6" smd rect
			(at -11.49985 2.7239)
			(size 0.7112 4.191)
			(layers "F.Cu" "F.Mask" "F.Paste")
		)
		(pad "B7" smd rect
			(at -10.49986 2.7239)
			(size 0.7112 4.191)
			(layers "F.Cu" "F.Mask" "F.Paste")
			(net "GND")
		)
		(pad "B8" smd rect
			(at -9.49986 2.7239)
			(size 0.7112 4.191)
			(layers "F.Cu" "F.Mask" "F.Paste")
			(net "+3.3V_PCIE")
		)
		(pad "B9" smd rect
			(at -8.49986 2.7239)
			(size 0.7112 4.191)
			(layers "F.Cu" "F.Mask" "F.Paste")
		)
		(pad "B10" smd rect
			(at -7.49986 2.7239)
			(size 0.7112 4.191)
			(layers "F.Cu" "F.Mask" "F.Paste")
		)
		(pad "B11" smd rect
			(at -6.49986 2.7239)
			(size 0.7112 4.191)
			(layers "F.Cu" "F.Mask" "F.Paste")
		)
		(pad "B12" smd rect
			(at -3.49987 2.7239)
			(size 0.7112 4.191)
			(layers "F.Cu" "F.Mask" "F.Paste")
		)
		(pad "B13" smd rect
			(at -2.49987 2.7239)
			(size 0.7112 4.191)
			(layers "F.Cu" "F.Mask" "F.Paste")
			(net "GND")
		)
		(pad "B14" smd rect
			(at -1.49987 2.7239)
			(size 0.7112 4.191)
			(layers "F.Cu" "F.Mask" "F.Paste")
			(net "PCIE_RX0_P")
		)
		(pad "B15" smd rect
			(at -0.49988 2.7239)
			(size 0.7112 4.191)
			(layers "F.Cu" "F.Mask" "F.Paste")
			(net "PCIE_RX0_N")
		)
		(pad "B16" smd rect
			(at 0.50012 2.7239)
			(size 0.7112 4.191)
			(layers "F.Cu" "F.Mask" "F.Paste")
			(net "GND")
		)
		(pad "B17" smd rect
			(at 1.50012 2.7239)
			(size 0.7112 4.191)
			(layers "F.Cu" "F.Mask" "F.Paste")
			(net "NetP2_B17")
		)
		(pad "B18" smd rect
			(at 2.50012 2.7239)
			(size 0.7112 4.191)
			(layers "F.Cu" "F.Mask" "F.Paste")
			(net "GND")
		)
		(pad "B19" smd rect
			(at 3.50012 2.7239)
			(size 0.7112 4.191)
			(layers "F.Cu" "F.Mask" "F.Paste")
			(net "PCIE_RX1_P")
		)
		(pad "B20" smd rect
			(at 4.50011 2.7239)
			(size 0.7112 4.191)
			(layers "F.Cu" "F.Mask" "F.Paste")
			(net "PCIE_RX1_N")
		)
		(pad "B21" smd rect
			(at 5.50011 2.7239)
			(size 0.7112 4.191)
			(layers "F.Cu" "F.Mask" "F.Paste")
			(net "GND")
		)
		(pad "B22" smd rect
			(at 6.50011 2.7239)
			(size 0.7112 4.191)
			(layers "F.Cu" "F.Mask" "F.Paste")
			(net "GND")
		)
		(pad "B23" smd rect
			(at 7.50011 2.7239)
			(size 0.7112 4.191)
			(layers "F.Cu" "F.Mask" "F.Paste")
			(net "PCIE_RX2_P")
		)
		(pad "B24" smd rect
			(at 8.50011 2.7239)
			(size 0.7112 4.191)
			(layers "F.Cu" "F.Mask" "F.Paste")
			(net "PCIE_RX2_N")
		)
		(pad "B25" smd rect
			(at 9.5001 2.7239)
			(size 0.7112 4.191)
			(layers "F.Cu" "F.Mask" "F.Paste")
			(net "GND")
		)
		(pad "B26" smd rect
			(at 10.5001 2.7239)
			(size 0.7112 4.191)
			(layers "F.Cu" "F.Mask" "F.Paste")
			(net "GND")
		)
		(pad "B27" smd rect
			(at 11.5001 2.7239)
			(size 0.7112 4.191)
			(layers "F.Cu" "F.Mask" "F.Paste")
			(net "PCIE_RX3_P")
		)
		(pad "B28" smd rect
			(at 12.5001 2.7239)
			(size 0.7112 4.191)
			(layers "F.Cu" "F.Mask" "F.Paste")
			(net "PCIE_RX3_N")
		)
		(pad "B29" smd rect
			(at 13.5001 2.7239)
			(size 0.7112 4.191)
			(layers "F.Cu" "F.Mask" "F.Paste")
			(net "GND")
		)
		(pad "B30" smd rect
			(at 14.50009 2.7239)
			(size 0.7112 4.191)
			(layers "F.Cu" "F.Mask" "F.Paste")
		)
		(pad "B31" smd rect
			(at 15.50009 2.2286)
			(size 0.7112 3.2004)
			(layers "F.Cu" "F.Mask" "F.Paste")
			(net "NetP2_B31")
		)
		(pad "B32" smd rect
			(at 16.50009 2.7239)
			(size 0.7112 4.191)
			(layers "F.Cu" "F.Mask" "F.Paste")
			(net "GND")
		)
	)
	(footprint "Passives:DIOM1608X06N"
		(layer "F.Cu")
		(at 85.112255 53.2366 90)
		(property "Reference" "D13"
			(at -1.55529 -1.375795 90)
			(unlocked yes)
			(layer "F.SilkS")
			(effects
				(font
					(size 0.762 0.762)
					(thickness 0.2286)
				)
				(justify left bottom)
			)
		)
		(property "Value" "RED"
			(at -4.13639 -0.5715 0)
			(unlocked yes)
			(layer "F.SilkS")
			(hide yes)
			(effects
				(font
					(size 1.524 1.524)
					(thickness 0.254)
				)
				(justify left bottom)
			)
		)
		(sheetname "USER_IO")
		(sheetfile "USER_IO.kicad_sch")
		(duplicate_pad_numbers_are_jumpers no)
		(fp_circle
			(center -1.275 -0.725)
			(end -1.225 -0.725)
			(stroke
				(width 0.1)
				(type solid)
			)
			(fill no)
			(layer "F.SilkS")
		)
		(pad "1" smd rect
			(at -0.725 0 180)
			(size 0.85 1)
			(layers "F.Cu" "F.Mask" "F.Paste")
			(net "NetD13_1")
		)
		(pad "2" smd rect
			(at 0.725 0 180)
			(size 0.85 1)
			(layers "F.Cu" "F.Mask" "F.Paste")
			(net "+3.3V")
		)
	)
	(footprint "Resistors:RESC1608X50N"
		(layer "F.Cu")
		(at 176.988595 53.7786)
		(property "Reference" "R33"
			(at 1.7 0.393345 0)
			(unlocked yes)
			(layer "F.SilkS")
			(effects
				(font
					(size 0.762 0.762)
					(thickness 0.2286)
				)
				(justify left bottom)
			)
		)
		(property "Value" "ERJ-3EKF1002V"
			(at -0.4445 3.72999 0)
			(unlocked yes)
			(layer "F.SilkS")
			(hide yes)
			(effects
				(font
					(size 1.524 1.524)
					(thickness 0.254)
				)
				(justify left bottom)
			)
		)
		(sheetname "USER_IO")
		(sheetfile "USER_IO.kicad_sch")
		(duplicate_pad_numbers_are_jumpers no)
		(fp_line
			(start 0 0.5)
			(end 0 -0.5)
			(stroke
				(width 0.1524)
				(type solid)
			)
			(layer "F.SilkS")
		)
		(pad "1" smd rect
			(at -0.69 0 90)
			(size 1 0.72)
			(layers "F.Cu" "F.Mask" "F.Paste")
			(net "NetR33_1")
		)
		(pad "2" smd rect
			(at 0.69 0 90)
			(size 1 0.72)
			(layers "F.Cu" "F.Mask" "F.Paste")
			(net "+3.3V")
		)
	)
	(footprint "Capacitors:CAPC2012X14N"
		(layer "F.Cu")
		(at 161.735595 89.0506 90)
		(property "Reference" "C75"
			(at 2.332545 -2.10771 0)
			(unlocked yes)
			(layer "F.SilkS")
			(effects
				(font
					(size 0.762 0.762)
					(thickness 0.2286)
				)
				(justify left bottom)
			)
		)
		(property "Value" "CAP_0805_22UF_16V"
			(at -3.52679 -1.5875 0)
			(unlocked yes)
			(layer "F.SilkS")
			(hide yes)
			(effects
				(font
					(size 1.524 1.524)
					(thickness 0.254)
				)
				(justify left bottom)
			)
		)
		(sheetname "MAC")
		(sheetfile "MAC.kicad_sch")
		(duplicate_pad_numbers_are_jumpers no)
		(fp_line
			(start -0.762 -0.9652)
			(end 0.762 -0.9652)
			(stroke
				(width 0.1524)
				(type solid)
			)
			(layer "F.SilkS")
		)
		(fp_line
			(start -0.762 0.9652)
			(end 0.762 0.9652)
			(stroke
				(width 0.1524)
				(type solid)
			)
			(layer "F.SilkS")
		)
		(pad "1" smd rect
			(at -0.9 0 180)
			(size 1.45 1.15)
			(layers "F.Cu" "F.Mask" "F.Paste")
			(net "GND")
		)
		(pad "2" smd rect
			(at 0.9 0 180)
			(size 1.45 1.15)
			(layers "F.Cu" "F.Mask" "F.Paste")
			(net "+3.3V_CLEAN")
		)
	)
	(footprint "Miscellaneous Devices:J1-0603"
		(layer "F.Cu")
		(at 82.288595 142.2786 180)
		(property "Reference" "R32"
			(at -1.6 -0.393345 0)
			(unlocked yes)
			(layer "F.SilkS")
			(effects
				(font
					(size 0.762 0.762)
					(thickness 0.2286)
				)
				(justify left bottom)
			)
		)
		(property "Value" "GPS1"
			(at 0.4445 -3.72999 0)
			(unlocked yes)
			(layer "F.SilkS")
			(hide yes)
			(effects
				(font
					(size 1.524 1.524)
					(thickness 0.254)
				)
				(justify left bottom)
			)
		)
		(sheetname "USER_IO")
		(sheetfile "USER_IO.kicad_sch")
		(duplicate_pad_numbers_are_jumpers no)
		(fp_line
			(start 0.2 0.35)
			(end -0.2 0.35)
			(stroke
				(width 0.2)
				(type solid)
			)
			(layer "F.SilkS")
		)
		(fp_line
			(start 0.2 -0.35)
			(end -0.2 -0.35)
			(stroke
				(width 0.2)
				(type solid)
			)
			(layer "F.SilkS")
		)
		(pad "1" smd rect
			(at -0.75 0 270)
			(size 0.9 0.7)
			(layers "F.Cu" "F.Mask" "F.Paste")
			(net "GPS1_TP1")
		)
		(pad "2" smd rect
			(at 0.75 0 270)
			(size 0.9 0.7)
			(layers "F.Cu" "F.Mask" "F.Paste")
			(net "ANT4")
		)
	)
	(footprint "Passives:IND_PM124SH"
		(layer "F.Cu")
		(at 219.012595 118.6416 90)
		(property "Reference" "L1"
			(at 5.456745 -8.78815 0)
			(unlocked yes)
			(layer "F.SilkS")
			(effects
				(font
					(size 0.762 0.762)
					(thickness 0.2286)
				)
				(justify left bottom)
			)
		)
		(property "Value" "PM124SH-100M-RC"
			(at -10.00379 -10.8331 0)
			(unlocked yes)
			(layer "F.SilkS")
			(hide yes)
			(effects
				(font
					(size 1.524 1.524)
					(thickness 0.254)
				)
				(justify left bottom)
			)
		)
		(sheetname "POWER")
		(sheetfile "POWER.kicad_sch")
		(duplicate_pad_numbers_are_jumpers no)
		(fp_line
			(start 6.681 -6.4)
			(end 6.681 6.4)
			(stroke
				(width 0.254)
				(type solid)
			)
			(layer "F.SilkS")
		)
		(fp_line
			(start -6.681 -6.4)
			(end 6.681 -6.4)
			(stroke
				(width 0.254)
				(type solid)
			)
			(layer "F.SilkS")
		)
		(fp_line
			(start -6.681 -6.4)
			(end -6.681 6.4)
			(stroke
				(width 0.254)
				(type solid)
			)
			(layer "F.SilkS")
		)
		(fp_line
			(start -6.681 6.4)
			(end 6.681 6.4)
			(stroke
				(width 0.254)
				(type solid)
			)
			(layer "F.SilkS")
		)
		(pad "1" smd rect
			(at -4.85 0 90)
			(size 2.9 5.4)
			(layers "F.Cu" "F.Mask" "F.Paste")
			(net "+5.0V")
		)
		(pad "2" smd rect
			(at 4.85 0 90)
			(size 2.9 5.4)
			(layers "F.Cu" "F.Mask" "F.Paste")
			(net "NetC4_2")
		)
	)
	(footprint "Vault:RESC1608X55X30NL15T15"
		(layer "F.Cu")
		(at 79.988595 56.9786 90)
		(property "Reference" "R28"
			(at -1.2 -1.206655 90)
			(unlocked yes)
			(layer "F.SilkS")
			(effects
				(font
					(size 0.762 0.762)
					(thickness 0.2286)
				)
				(justify left bottom)
			)
		)
		(property "Value" "200 OHM"
			(at -3.72999 -0.4445 0)
			(unlocked yes)
			(layer "F.SilkS")
			(hide yes)
			(effects
				(font
					(size 1.524 1.524)
					(thickness 0.254)
				)
				(justify left bottom)
			)
		)
		(sheetname "USER_IO")
		(sheetfile "USER_IO.kicad_sch")
		(duplicate_pad_numbers_are_jumpers no)
		(pad "1" smd rect
			(at -0.675 0 180)
			(size 0.95 0.8)
			(layers "F.Cu" "F.Mask" "F.Paste")
			(net "LED2")
		)
		(pad "2" smd rect
			(at 0.675 0 180)
			(size 0.95 0.8)
			(layers "F.Cu" "F.Mask" "F.Paste")
			(net "NetD12_1")
		)
	)
	(footprint "Connectors:3PINV-100"
		(layer "F.Cu")
		(at 95.513595 52.5286 -90)
		(property "Reference" "JP1"
			(at -0.981655 3.35 0)
			(unlocked yes)
			(layer "F.SilkS")
			(effects
				(font
					(size 0.762 0.762)
					(thickness 0.2286)
				)
				(justify left bottom)
			)
		)
		(property "Value" "JUMPER_3PIN"
			(at 9.49579 1.7145 0)
			(unlocked yes)
			(layer "F.SilkS")
			(hide yes)
			(effects
				(font
					(size 1.524 1.524)
					(thickness 0.254)
				)
				(justify left bottom)
			)
		)
		(sheetname "GPS_IMU_SENSORS")
		(sheetfile "GPS_IMU_SENSORS.kicad_sch")
		(duplicate_pad_numbers_are_jumpers no)
		(fp_line
			(start -1.27 1.27)
			(end -1.27 -1.27)
			(stroke
				(width 0.1524)
				(type solid)
			)
			(layer "F.SilkS")
		)
		(fp_line
			(start 6.35 1.27)
			(end -1.27 1.27)
			(stroke
				(width 0.1524)
				(type solid)
			)
			(layer "F.SilkS")
		)
		(fp_line
			(start 6.35 1.27)
			(end 6.35 -1.27)
			(stroke
				(width 0.1524)
				(type solid)
			)
			(layer "F.SilkS")
		)
		(fp_line
			(start 6.35 -1.27)
			(end -1.27 -1.27)
			(stroke
				(width 0.1524)
				(type solid)
			)
			(layer "F.SilkS")
		)
		(pad "1" thru_hole rect
			(at 0 0 270)
			(size 1.397 1.397)
			(drill 0.762)
			(layers "*.Cu" "*.Mask")
			(remove_unused_layers no)
			(net "GPS1_TX")
		)
		(pad "2" thru_hole circle
			(at 2.54 0 270)
			(size 1.397 1.397)
			(drill 0.762)
			(layers "*.Cu" "*.Mask")
			(remove_unused_layers no)
			(net "NetJP1_2")
			(thermal_bridge_angle 90)
		)
		(pad "3" thru_hole circle
			(at 5.08 0 270)
			(size 1.397 1.397)
			(drill 0.762)
			(layers "*.Cu" "*.Mask")
			(remove_unused_layers no)
			(net "NetJP1_3")
			(thermal_bridge_angle 90)
		)
	)
	(footprint "Capacitors:CAPC2012X14N"
		(layer "F.Cu")
		(at 152.337595 142.1366 180)
		(property "Reference" "C62"
			(at 4.849 -0.335345 0)
			(unlocked yes)
			(layer "F.SilkS")
			(effects
				(font
					(size 0.762 0.762)
					(thickness 0.2286)
				)
				(justify left bottom)
			)
		)
		(property "Value" "CAP_0805_10UF_25V"
			(at 1.5875 -3.52679 0)
			(unlocked yes)
			(layer "F.SilkS")
			(hide yes)
			(effects
				(font
					(size 1.524 1.524)
					(thickness 0.254)
				)
				(justify left bottom)
			)
		)
		(sheetname "MAC")
		(sheetfile "MAC.kicad_sch")
		(duplicate_pad_numbers_are_jumpers no)
		(fp_line
			(start 0.762 0.9652)
			(end -0.762 0.9652)
			(stroke
				(width 0.1524)
				(type solid)
			)
			(layer "F.SilkS")
		)
		(fp_line
			(start 0.762 -0.9652)
			(end -0.762 -0.9652)
			(stroke
				(width 0.1524)
				(type solid)
			)
			(layer "F.SilkS")
		)
		(pad "1" smd rect
			(at -0.9 0 270)
			(size 1.45 1.15)
			(layers "F.Cu" "F.Mask" "F.Paste")
			(net "+5.0V")
		)
		(pad "2" smd rect
			(at 0.9 0 270)
			(size 1.45 1.15)
			(layers "F.Cu" "F.Mask" "F.Paste")
			(net "GND")
		)
	)
)
